(kicad_pcb
	(version 20260206)
	(generator "pcbnew")
	(generator_version "10.0")
	(general
		(thickness 1.6)
		(legacy_teardrops no)
	)
	(paper "A4")
	(title_block
		(title "Wiwynn_Tioga_Pass_MB.brd")
		(comment 1 "Tioga Pass / footprints 415-421 of 4770")
	)
	(layers
		(0 "F.Cu" signal "TOP")
		(4 "In1.Cu" signal "L2GND")
		(6 "In2.Cu" signal "L3")
		(8 "In3.Cu" signal "L4GND")
		(10 "In4.Cu" signal "L5")
		(12 "In5.Cu" signal "L6GND")
		(14 "In6.Cu" signal "L7VCC")
		(16 "In7.Cu" signal "L8VCC")
		(18 "In8.Cu" signal "L9GND")
		(20 "In9.Cu" signal "L10")
		(22 "In10.Cu" signal "L11GND")
		(24 "In11.Cu" signal "L12")
		(26 "In12.Cu" signal "L13GND")
		(2 "B.Cu" signal "BOTTOM")
		(9 "F.Adhes" user "F.Adhesive")
		(11 "B.Adhes" user "B.Adhesive")
		(13 "F.Paste" user "Package Geometry/Pastemask Top")
		(15 "B.Paste" user "Package Geometry/Pastemask Bottom")
		(5 "F.SilkS" user "Ref Des/Silkscreen Top")
		(7 "B.SilkS" user "Ref Des/Silkscreen Bottom")
		(1 "F.Mask" user "Board Geometry/Soldermask Top")
		(3 "B.Mask" user "Board Geometry/Soldermask Bottom")
		(17 "Dwgs.User" user "User.Drawings")
		(19 "Cmts.User" user "User.Comments")
		(21 "Eco1.User" user "User.Eco1")
		(23 "Eco2.User" user "User.Eco2")
		(25 "Edge.Cuts" user "Board Geometry/Outline")
		(27 "Margin" user)
		(31 "F.CrtYd" user "Package Geometry/Place Bound Top")
		(29 "B.CrtYd" user "Package Geometry/Place Bound Bottom")
		(35 "F.Fab" user "Ref Des/Assembly Top")
		(33 "B.Fab" user "Ref Des/Assembly Bottom")
	)
	(footprint ""
		(layer "F.Cu")
		(at 380.032768 -32.3215 -90)
		(property "Reference" "C8F12"
			(at 0 0 270)
			(layer "F.SilkS")
			(hide yes)
			(effects
				(font
					(size 1.27 1.27)
				)
			)
		)
		(property "Value" ""
			(at 0 0 270)
			(layer "F.Fab")
			(effects
				(font
					(size 1.27 1.27)
				)
			)
		)
		(duplicate_pad_numbers_are_jumpers no)
		(fp_poly
			(pts
				(xy 0.3048 -0.1016) (xy 0.3048 0.9906) (xy -0.3048 0.9906) (xy -0.3048 -0.1016)
			)
			(stroke
				(width 0)
				(type default)
			)
			(fill no)
			(layer "F.CrtYd")
		)
		(fp_line
			(start -0.3048 0.9906)
			(end 0.3048 0.9906)
			(stroke
				(width 0.1)
				(type default)
			)
			(layer "F.Fab")
		)
		(fp_line
			(start 0.3048 0.9906)
			(end 0.3048 -0.1016)
			(stroke
				(width 0.1)
				(type default)
			)
			(layer "F.Fab")
		)
		(fp_line
			(start -0.3048 -0.1016)
			(end -0.3048 0.9906)
			(stroke
				(width 0.1)
				(type default)
			)
			(layer "F.Fab")
		)
		(fp_line
			(start 0.3048 -0.1016)
			(end -0.3048 -0.1016)
			(stroke
				(width 0.1)
				(type default)
			)
			(layer "F.Fab")
		)
		(pad "1" smd rect
			(at 0 0 270)
			(size 0.508 0.508)
			(layers "F.Cu" "F.Mask" "F.Paste")
			(net "P3E_PCH_TX_0_DN")
		)
		(pad "2" smd rect
			(at 0 0.889 270)
			(size 0.508 0.508)
			(layers "F.Cu" "F.Mask" "F.Paste")
			(net "P3E_PCH_M2_SATA6G_TX_R_DN")
		)
		(zone
			(layer "F.Cu")
			(hatch none 0.5)
			(connect_pads
				(clearance 0)
			)
			(min_thickness 0.25)
			(keepout
				(tracks not_allowed)
				(vias allowed)
				(pads allowed)
				(copperpour not_allowed)
				(footprints allowed)
			)
			(placement
				(enabled no)
				(sheetname "")
			)
			(fill
				(thermal_gap 0.5)
				(thermal_bridge_width 0.5)
				(island_removal_mode 0)
			)
			(polygon
				(pts
					(xy 379.397768 -32.5755) (xy 379.397768 -32.0675) (xy 379.778768 -32.0675) (xy 379.778768 -32.5755)
				)
			)
		)
		(zone
			(layer "F.Cu")
			(hatch none 0.5)
			(connect_pads
				(clearance 0)
			)
			(min_thickness 0.25)
			(keepout
				(tracks allowed)
				(vias not_allowed)
				(pads allowed)
				(copperpour not_allowed)
				(footprints allowed)
			)
			(placement
				(enabled no)
				(sheetname "")
			)
			(fill
				(thermal_gap 0.5)
				(thermal_bridge_width 0.5)
				(island_removal_mode 0)
			)
			(polygon
				(pts
					(xy 379.778768 -32.5755) (xy 379.778768 -32.0675) (xy 379.397768 -32.0675) (xy 379.397768 -32.5755)
				)
			)
		)
	)
	(footprint ""
		(layer "F.Cu")
		(at 190.754 -86.741 -90)
		(property "Reference" "C4D2"
			(at -0.762 7.72033 90)
			(unlocked yes)
			(layer "F.SilkS")
			(effects
				(font
					(size 0.7874 0.5842)
					(thickness 0.1524)
				)
				(justify left)
			)
		)
		(property "Value" ""
			(at 0 0 270)
			(layer "F.Fab")
			(effects
				(font
					(size 1.27 1.27)
				)
			)
		)
		(duplicate_pad_numbers_are_jumpers no)
		(fp_line
			(start -3.400044 6.067044)
			(end -0.9017 6.067044)
			(stroke
				(width 0.1524)
				(type default)
			)
			(layer "F.SilkS")
		)
		(fp_line
			(start 0.9017 6.067044)
			(end 3.400044 6.067044)
			(stroke
				(width 0.1524)
				(type default)
			)
			(layer "F.SilkS")
		)
		(fp_line
			(start 3.400044 6.067044)
			(end 3.400044 0.028956)
			(stroke
				(width 0.1524)
				(type default)
			)
			(layer "F.SilkS")
		)
		(fp_line
			(start -0.9017 1.587754)
			(end -0.7239 1.587754)
			(stroke
				(width 0.1524)
				(type default)
			)
			(layer "F.SilkS")
		)
		(fp_line
			(start 0.7239 1.587754)
			(end 0.9017 1.587754)
			(stroke
				(width 0.1524)
				(type default)
			)
			(layer "F.SilkS")
		)
		(fp_line
			(start 0.9017 1.587754)
			(end 0.9017 -1.714246)
			(stroke
				(width 0.1524)
				(type default)
			)
			(layer "F.SilkS")
		)
		(fp_line
			(start -3.400044 0.028956)
			(end -3.400044 6.067044)
			(stroke
				(width 0.1524)
				(type default)
			)
			(layer "F.SilkS")
		)
		(fp_line
			(start 3.400044 0.028956)
			(end 2.638044 -0.733044)
			(stroke
				(width 0.1524)
				(type default)
			)
			(layer "F.SilkS")
		)
		(fp_line
			(start -2.638044 -0.733044)
			(end -3.400044 0.028956)
			(stroke
				(width 0.1524)
				(type default)
			)
			(layer "F.SilkS")
		)
		(fp_line
			(start -0.9017 -0.733044)
			(end -2.638044 -0.733044)
			(stroke
				(width 0.1524)
				(type default)
			)
			(layer "F.SilkS")
		)
		(fp_line
			(start 2.638044 -0.733044)
			(end 0.9017 -0.733044)
			(stroke
				(width 0.1524)
				(type default)
			)
			(layer "F.SilkS")
		)
		(fp_line
			(start -0.9017 -1.714246)
			(end -0.9017 1.587754)
			(stroke
				(width 0.1524)
				(type default)
			)
			(layer "F.SilkS")
		)
		(fp_line
			(start -0.7239 -1.714246)
			(end -0.9017 -1.714246)
			(stroke
				(width 0.1524)
				(type default)
			)
			(layer "F.SilkS")
		)
		(fp_line
			(start 0.9017 -1.714246)
			(end 0.7239 -1.714246)
			(stroke
				(width 0.1524)
				(type default)
			)
			(layer "F.SilkS")
		)
		(fp_poly
			(pts
				(xy -3.400044 6.067044) (xy 3.400044 6.067044) (xy 3.400044 0.028956) (xy 2.638044 -0.733044) (xy -2.638044 -0.733044)
				(xy -3.400044 0.028956)
			)
			(stroke
				(width 0)
				(type default)
			)
			(fill no)
			(layer "F.CrtYd")
		)
		(fp_line
			(start -3.400044 6.067044)
			(end 3.400044 6.067044)
			(stroke
				(width 0.1)
				(type default)
			)
			(layer "F.Fab")
		)
		(fp_line
			(start 3.400044 6.067044)
			(end 3.400044 0.028956)
			(stroke
				(width 0.1)
				(type default)
			)
			(layer "F.Fab")
		)
		(fp_line
			(start -3.400044 0.028956)
			(end -3.400044 6.067044)
			(stroke
				(width 0.1)
				(type default)
			)
			(layer "F.Fab")
		)
		(fp_line
			(start 3.400044 0.028956)
			(end 2.638044 -0.733044)
			(stroke
				(width 0.1)
				(type default)
			)
			(layer "F.Fab")
		)
		(fp_line
			(start -2.638044 -0.733044)
			(end -3.400044 0.028956)
			(stroke
				(width 0.1)
				(type default)
			)
			(layer "F.Fab")
		)
		(fp_line
			(start 2.638044 -0.733044)
			(end -2.638044 -0.733044)
			(stroke
				(width 0.1)
				(type default)
			)
			(layer "F.Fab")
		)
		(fp_circle
			(center 0 2.667)
			(end 0 -0.733044)
			(stroke
				(width 0.1)
				(type default)
			)
			(fill no)
			(layer "F.Fab")
		)
		(pad "1" smd rect
			(at 0 0 270)
			(size 0.7874 3.429)
			(layers "F.Cu" "F.Mask" "F.Paste")
			(net "VR_FET_SW_P12V_STBY_PVCCIN_CPU0")
		)
		(pad "2" smd rect
			(at 0 5.334 270)
			(size 0.7874 3.429)
			(layers "F.Cu" "F.Mask" "F.Paste")
			(net "GND")
		)
	)
	(footprint ""
		(layer "F.Cu")
		(at 399.923 -149.225 180)
		(property "Reference" "R8A7"
			(at 0 0 180)
			(layer "F.SilkS")
			(hide yes)
			(effects
				(font
					(size 1.27 1.27)
				)
			)
		)
		(property "Value" ""
			(at 0 0 180)
			(layer "F.Fab")
			(effects
				(font
					(size 1.27 1.27)
				)
			)
		)
		(duplicate_pad_numbers_are_jumpers no)
		(fp_poly
			(pts
				(xy -0.2794 -0.1016) (xy 0.2794 -0.1016) (xy 0.2794 0.9906) (xy -0.2794 0.9906)
			)
			(stroke
				(width 0)
				(type default)
			)
			(fill no)
			(layer "F.CrtYd")
		)
		(fp_line
			(start 0.2794 0.9906)
			(end 0.2794 -0.1016)
			(stroke
				(width 0.1)
				(type default)
			)
			(layer "F.Fab")
		)
		(fp_line
			(start 0.2794 -0.1016)
			(end -0.2794 -0.1016)
			(stroke
				(width 0.1)
				(type default)
			)
			(layer "F.Fab")
		)
		(fp_line
			(start -0.2794 0.9906)
			(end 0.2794 0.9906)
			(stroke
				(width 0.1)
				(type default)
			)
			(layer "F.Fab")
		)
		(fp_line
			(start -0.2794 -0.1016)
			(end -0.2794 0.9906)
			(stroke
				(width 0.1)
				(type default)
			)
			(layer "F.Fab")
		)
		(pad "1" smd rect
			(at 0 0 180)
			(size 0.508 0.508)
			(layers "F.Cu" "F.Mask" "F.Paste")
			(net "P3V3_STBY")
		)
		(pad "2" smd rect
			(at 0 0.889 180)
			(size 0.508 0.508)
			(layers "F.Cu" "F.Mask" "F.Paste")
			(net "VR_PVNN_PCH_VREN")
		)
		(zone
			(layer "F.Cu")
			(hatch none 0.5)
			(connect_pads
				(clearance 0)
			)
			(min_thickness 0.25)
			(keepout
				(tracks not_allowed)
				(vias allowed)
				(pads allowed)
				(copperpour not_allowed)
				(footprints allowed)
			)
			(placement
				(enabled no)
				(sheetname "")
			)
			(fill
				(thermal_gap 0.5)
				(thermal_bridge_width 0.5)
				(island_removal_mode 0)
			)
			(polygon
				(pts
					(xy 400.177 -149.86) (xy 399.669 -149.86) (xy 399.669 -149.479) (xy 400.177 -149.479)
				)
			)
		)
		(zone
			(layer "F.Cu")
			(hatch none 0.5)
			(connect_pads
				(clearance 0)
			)
			(min_thickness 0.25)
			(keepout
				(tracks allowed)
				(vias not_allowed)
				(pads allowed)
				(copperpour not_allowed)
				(footprints allowed)
			)
			(placement
				(enabled no)
				(sheetname "")
			)
			(fill
				(thermal_gap 0.5)
				(thermal_bridge_width 0.5)
				(island_removal_mode 0)
			)
			(polygon
				(pts
					(xy 400.177 -149.479) (xy 399.669 -149.479) (xy 399.669 -149.86) (xy 400.177 -149.86)
				)
			)
		)
	)
	(footprint ""
		(layer "F.Cu")
		(at 105.65384 -77.636116)
		(property "Reference" "C2D29"
			(at 0 0 0)
			(layer "F.SilkS")
			(hide yes)
			(effects
				(font
					(size 1.27 1.27)
				)
			)
		)
		(property "Value" ""
			(at 0 0 0)
			(layer "F.Fab")
			(effects
				(font
					(size 1.27 1.27)
				)
			)
		)
		(duplicate_pad_numbers_are_jumpers no)
		(fp_poly
			(pts
				(xy -0.4953 -0.2032) (xy 0.4953 -0.2032) (xy 0.4953 1.6002) (xy -0.4953 1.6002)
			)
			(stroke
				(width 0)
				(type default)
			)
			(fill no)
			(layer "F.CrtYd")
		)
		(fp_line
			(start -0.4953 -0.2032)
			(end 0.4953 -0.2032)
			(stroke
				(width 0.1)
				(type default)
			)
			(layer "F.Fab")
		)
		(fp_line
			(start -0.4953 1.6002)
			(end -0.4953 -0.2032)
			(stroke
				(width 0.1)
				(type default)
			)
			(layer "F.Fab")
		)
		(fp_line
			(start 0.4953 -0.2032)
			(end 0.4953 1.6002)
			(stroke
				(width 0.1)
				(type default)
			)
			(layer "F.Fab")
		)
		(fp_line
			(start 0.4953 1.6002)
			(end -0.4953 1.6002)
			(stroke
				(width 0.1)
				(type default)
			)
			(layer "F.Fab")
		)
		(pad "1" smd rect
			(at 0 0)
			(size 0.762 0.889)
			(layers "F.Cu" "F.Mask" "F.Paste")
			(net "PVCCMCP_CPU1")
		)
		(pad "2" smd rect
			(at 0 1.397)
			(size 0.762 0.889)
			(layers "F.Cu" "F.Mask" "F.Paste")
			(net "GND")
		)
		(zone
			(layer "F.Cu")
			(hatch none 0.5)
			(connect_pads
				(clearance 0)
			)
			(min_thickness 0.25)
			(keepout
				(tracks not_allowed)
				(vias allowed)
				(pads allowed)
				(copperpour not_allowed)
				(footprints allowed)
			)
			(placement
				(enabled no)
				(sheetname "")
			)
			(fill
				(thermal_gap 0.5)
				(thermal_bridge_width 0.5)
				(island_removal_mode 0)
			)
			(polygon
				(pts
					(xy 105.27284 -77.191616) (xy 106.03484 -77.191616) (xy 106.03484 -76.683616) (xy 105.27284 -76.683616)
				)
			)
		)
	)
	(footprint ""
		(layer "F.Cu")
		(at 194.749928 -67.97294 -90)
		(property "Reference" "C4D48"
			(at 0 0 270)
			(layer "F.SilkS")
			(hide yes)
			(effects
				(font
					(size 1.27 1.27)
				)
			)
		)
		(property "Value" ""
			(at 0 0 270)
			(layer "F.Fab")
			(effects
				(font
					(size 1.27 1.27)
				)
			)
		)
		(duplicate_pad_numbers_are_jumpers no)
		(fp_poly
			(pts
				(xy 0.3048 -0.1016) (xy 0.3048 0.9906) (xy -0.3048 0.9906) (xy -0.3048 -0.1016)
			)
			(stroke
				(width 0)
				(type default)
			)
			(fill no)
			(layer "F.CrtYd")
		)
		(fp_line
			(start -0.3048 0.9906)
			(end 0.3048 0.9906)
			(stroke
				(width 0.1)
				(type default)
			)
			(layer "F.Fab")
		)
		(fp_line
			(start 0.3048 0.9906)
			(end 0.3048 -0.1016)
			(stroke
				(width 0.1)
				(type default)
			)
			(layer "F.Fab")
		)
		(fp_line
			(start -0.3048 -0.1016)
			(end -0.3048 0.9906)
			(stroke
				(width 0.1)
				(type default)
			)
			(layer "F.Fab")
		)
		(fp_line
			(start 0.3048 -0.1016)
			(end -0.3048 -0.1016)
			(stroke
				(width 0.1)
				(type default)
			)
			(layer "F.Fab")
		)
		(pad "1" smd rect
			(at 0 0 270)
			(size 0.508 0.508)
			(layers "F.Cu" "F.Mask" "F.Paste")
			(net "VR_FET_SW_P12V_STBY_PVCCIN_CPU0")
		)
		(pad "2" smd rect
			(at 0 0.889 270)
			(size 0.508 0.508)
			(layers "F.Cu" "F.Mask" "F.Paste")
			(net "GND")
		)
		(zone
			(layer "F.Cu")
			(hatch none 0.5)
			(connect_pads
				(clearance 0)
			)
			(min_thickness 0.25)
			(keepout
				(tracks not_allowed)
				(vias allowed)
				(pads allowed)
				(copperpour not_allowed)
				(footprints allowed)
			)
			(placement
				(enabled no)
				(sheetname "")
			)
			(fill
				(thermal_gap 0.5)
				(thermal_bridge_width 0.5)
				(island_removal_mode 0)
			)
			(polygon
				(pts
					(xy 194.114928 -68.22694) (xy 194.114928 -67.71894) (xy 194.495928 -67.71894) (xy 194.495928 -68.22694)
				)
			)
		)
		(zone
			(layer "F.Cu")
			(hatch none 0.5)
			(connect_pads
				(clearance 0)
			)
			(min_thickness 0.25)
			(keepout
				(tracks allowed)
				(vias not_allowed)
				(pads allowed)
				(copperpour not_allowed)
				(footprints allowed)
			)
			(placement
				(enabled no)
				(sheetname "")
			)
			(fill
				(thermal_gap 0.5)
				(thermal_bridge_width 0.5)
				(island_removal_mode 0)
			)
			(polygon
				(pts
					(xy 194.495928 -68.22694) (xy 194.495928 -67.71894) (xy 194.114928 -67.71894) (xy 194.114928 -68.22694)
				)
			)
		)
	)
	(footprint ""
		(layer "F.Cu")
		(at 465.7344 3.9878 90)
		(property "Reference" "R9G35"
			(at 0 0 90)
			(layer "F.SilkS")
			(hide yes)
			(effects
				(font
					(size 1.27 1.27)
				)
			)
		)
		(property "Value" ""
			(at 0 0 90)
			(layer "F.Fab")
			(effects
				(font
					(size 1.27 1.27)
				)
			)
		)
		(duplicate_pad_numbers_are_jumpers no)
		(fp_poly
			(pts
				(xy -0.2794 -0.1016) (xy 0.2794 -0.1016) (xy 0.2794 0.9906) (xy -0.2794 0.9906)
			)
			(stroke
				(width 0)
				(type default)
			)
			(fill no)
			(layer "F.CrtYd")
		)
		(fp_line
			(start 0.2794 -0.1016)
			(end -0.2794 -0.1016)
			(stroke
				(width 0.1)
				(type default)
			)
			(layer "F.Fab")
		)
		(fp_line
			(start -0.2794 -0.1016)
			(end -0.2794 0.9906)
			(stroke
				(width 0.1)
				(type default)
			)
			(layer "F.Fab")
		)
		(fp_line
			(start 0.2794 0.9906)
			(end 0.2794 -0.1016)
			(stroke
				(width 0.1)
				(type default)
			)
			(layer "F.Fab")
		)
		(fp_line
			(start -0.2794 0.9906)
			(end 0.2794 0.9906)
			(stroke
				(width 0.1)
				(type default)
			)
			(layer "F.Fab")
		)
		(pad "1" smd rect
			(at 0 0 90)
			(size 0.508 0.508)
			(layers "F.Cu" "F.Mask" "F.Paste")
			(net "P3V3_STBY")
		)
		(pad "2" smd rect
			(at 0 0.889 90)
			(size 0.508 0.508)
			(layers "F.Cu" "F.Mask" "F.Paste")
			(net "FM_BATTERY_SENSE_EN_N")
		)
		(zone
			(layer "F.Cu")
			(hatch none 0.5)
			(connect_pads
				(clearance 0)
			)
			(min_thickness 0.25)
			(keepout
				(tracks allowed)
				(vias not_allowed)
				(pads allowed)
				(copperpour not_allowed)
				(footprints allowed)
			)
			(placement
				(enabled no)
				(sheetname "")
			)
			(fill
				(thermal_gap 0.5)
				(thermal_bridge_width 0.5)
				(island_removal_mode 0)
			)
			(polygon
				(pts
					(xy 465.9884 4.2418) (xy 465.9884 3.7338) (xy 466.3694 3.7338) (xy 466.3694 4.2418)
				)
			)
		)
		(zone
			(layer "F.Cu")
			(hatch none 0.5)
			(connect_pads
				(clearance 0)
			)
			(min_thickness 0.25)
			(keepout
				(tracks not_allowed)
				(vias allowed)
				(pads allowed)
				(copperpour not_allowed)
				(footprints allowed)
			)
			(placement
				(enabled no)
				(sheetname "")
			)
			(fill
				(thermal_gap 0.5)
				(thermal_bridge_width 0.5)
				(island_removal_mode 0)
			)
			(polygon
				(pts
					(xy 466.3694 4.2418) (xy 466.3694 3.7338) (xy 465.9884 3.7338) (xy 465.9884 4.2418)
				)
			)
		)
	)
	(footprint ""
		(layer "F.Cu")
		(at 403.719792 -10.917936)
		(property "Reference" "C8G4"
			(at 0 0 0)
			(layer "F.SilkS")
			(hide yes)
			(effects
				(font
					(size 1.27 1.27)
				)
			)
		)
		(property "Value" ""
			(at 0 0 0)
			(layer "F.Fab")
			(effects
				(font
					(size 1.27 1.27)
				)
			)
		)
		(duplicate_pad_numbers_are_jumpers no)
		(fp_rect
			(start -0.3048 0.9906)
			(end 0.3048 -0.1016)
			(stroke
				(width 0)
				(type default)
			)
			(fill no)
			(layer "F.CrtYd")
		)
		(fp_line
			(start -0.3048 -0.1016)
			(end -0.3048 0.9906)
			(stroke
				(width 0.1)
				(type default)
			)
			(layer "F.Fab")
		)
		(fp_line
			(start -0.3048 0.9906)
			(end 0.3048 0.9906)
			(stroke
				(width 0.1)
				(type default)
			)
			(layer "F.Fab")
		)
		(fp_line
			(start 0.3048 -0.1016)
			(end -0.3048 -0.1016)
			(stroke
				(width 0.1)
				(type default)
			)
			(layer "F.Fab")
		)
		(fp_line
			(start 0.3048 0.9906)
			(end 0.3048 -0.1016)
			(stroke
				(width 0.1)
				(type default)
			)
			(layer "F.Fab")
		)
		(pad "1" smd rect
			(at 0 0)
			(size 0.508 0.508)
			(layers "F.Cu" "F.Mask" "F.Paste")
			(net "P3E_CPU0_PE2_SS_TXN<3>")
		)
		(pad "2" smd rect
			(at 0 0.889)
			(size 0.508 0.508)
			(layers "F.Cu" "F.Mask" "F.Paste")
			(net "P3E_CPU0_PE2_SS_C_TXN<3>")
		)
		(zone
			(layer "F.Cu")
			(hatch none 0.5)
			(connect_pads
				(clearance 0)
			)
			(min_thickness 0.25)
			(keepout
				(tracks allowed)
				(vias not_allowed)
				(pads allowed)
				(copperpour not_allowed)
				(footprints allowed)
			)
			(placement
				(enabled no)
				(sheetname "")
			)
			(fill
				(thermal_gap 0.5)
				(thermal_bridge_width 0.5)
				(island_removal_mode 0)
			)
			(polygon
				(pts
					(xy 403.465792 -10.282936) (xy 403.973792 -10.282936) (xy 403.973792 -10.663936) (xy 403.465792 -10.663936)
				)
			)
		)
		(zone
			(layer "F.Cu")
			(hatch none 0.5)
			(connect_pads
				(clearance 0)
			)
			(min_thickness 0.25)
			(keepout
				(tracks not_allowed)
				(vias allowed)
				(pads allowed)
				(copperpour not_allowed)
				(footprints allowed)
			)
			(placement
				(enabled no)
				(sheetname "")
			)
			(fill
				(thermal_gap 0.5)
				(thermal_bridge_width 0.5)
				(island_removal_mode 0)
			)
			(polygon
				(pts
					(xy 403.465792 -10.282936) (xy 403.973792 -10.282936) (xy 403.973792 -10.663936) (xy 403.465792 -10.663936)
				)
			)
		)
	)
)
